#ISCELL
  mstr_misc dns *
  *
#ISCELL
  pure_quanta quanta_title_block_c *
  *
#CELL
  pure_quanta me_dummy_symbol *
  page59_i27
#CELL
  pure_quanta me_dummy_symbol *
  page59_i28
#CELL
  pure_quanta me_dummy_symbol *
  page59_i29
#CELL
  pure_quanta me_dummy_symbol *
  page59_i34
#CELL
  pure_quanta dummy_symbol *
  page59_i35
#CELL
  pure_quanta dummy_symbol *
  page59_i36
#CELL
  pure_quanta dummy_symbol *
  page59_i37
